(kicad_pcb
	(version 20260206)
	(generator "pcbnew")
	(generator_version "10.0")
	(general
		(thickness 1.6)
		(legacy_teardrops no)
	)
	(paper "A4")
	(title_block
		(title "04192023_DAF0TMB3IC0_F0TG_MB_C_brd_V02_OCP.brd")
		(comment 1 "Grand Teton / footprints 3244-3248 of 8354")
	)
	(layers
		(0 "F.Cu" signal "TOP")
		(4 "In1.Cu" signal "GND")
		(6 "In2.Cu" signal "IN1")
		(8 "In3.Cu" signal "GND1")
		(10 "In4.Cu" signal "IN2")
		(12 "In5.Cu" signal "GND2")
		(14 "In6.Cu" signal "IN3")
		(16 "In7.Cu" signal "GND3")
		(18 "In8.Cu" signal "VCC")
		(20 "In9.Cu" signal "VCC1")
		(22 "In10.Cu" signal "GND4")
		(24 "In11.Cu" signal "IN4")
		(26 "In12.Cu" signal "GND5")
		(28 "In13.Cu" signal "IN5")
		(30 "In14.Cu" signal "GND6")
		(32 "In15.Cu" signal "IN6")
		(34 "In16.Cu" signal "GND7")
		(2 "B.Cu" signal "BOTTOM")
		(9 "F.Adhes" user "F.Adhesive")
		(11 "B.Adhes" user "B.Adhesive")
		(13 "F.Paste" user "Package Geometry/Pastemask Top")
		(15 "B.Paste" user "Package Geometry/Pastemask Bottom")
		(5 "F.SilkS" user "Ref Des/Silkscreen Top")
		(7 "B.SilkS" user "Ref Des/Silkscreen Bottom")
		(1 "F.Mask" user "Board Geometry/Soldermask Top")
		(3 "B.Mask" user "Board Geometry/Soldermask Bottom")
		(17 "Dwgs.User" user "User.Drawings")
		(19 "Cmts.User" user "User.Comments")
		(21 "Eco1.User" user "User.Eco1")
		(23 "Eco2.User" user "User.Eco2")
		(25 "Edge.Cuts" user "Board Geometry/Outline")
		(27 "Margin" user)
		(31 "F.CrtYd" user "Package Geometry/Place Bound Top")
		(29 "B.CrtYd" user "Package Geometry/Place Bound Bottom")
		(35 "F.Fab" user "Ref Des/Assembly Top")
		(33 "B.Fab" user "Ref Des/Assembly Bottom")
	)
	(footprint ""
		(layer "F.Cu")
		(at 316.935866 -416.899344 -90)
		(property "Reference" "C6509"
			(at 0 0 270)
			(layer "F.SilkS")
			(hide yes)
			(effects
				(font
					(size 1.27 1.27)
				)
			)
		)
		(property "Value" ""
			(at 0 0 270)
			(layer "F.Fab")
			(effects
				(font
					(size 1.27 1.27)
				)
			)
		)
		(duplicate_pad_numbers_are_jumpers no)
		(fp_line
			(start -0.299974 0.150114)
			(end -0.299974 -0.150114)
			(stroke
				(width 0.1)
				(type default)
			)
			(layer "F.Fab")
		)
		(fp_line
			(start 0.299974 0.150114)
			(end -0.299974 0.150114)
			(stroke
				(width 0.1)
				(type default)
			)
			(layer "F.Fab")
		)
		(fp_line
			(start -0.299974 -0.150114)
			(end 0.299974 -0.150114)
			(stroke
				(width 0.1)
				(type default)
			)
			(layer "F.Fab")
		)
		(fp_line
			(start 0.299974 -0.150114)
			(end 0.299974 0.150114)
			(stroke
				(width 0.1)
				(type default)
			)
			(layer "F.Fab")
		)
		(pad "1" smd rect
			(at -0.2667 0 270)
			(size 0.3048 0.381)
			(layers "F.Cu" "F.Mask" "F.Paste")
			(net "P5E_CPU0_P0_TX_BUF_C_DP<4>")
		)
		(pad "2" smd rect
			(at 0.2667 0 270)
			(size 0.3048 0.381)
			(layers "F.Cu" "F.Mask" "F.Paste")
			(net "P5E_CPU0_P0_TX_BUF_DP<4>")
		)
	)
	(footprint ""
		(layer "F.Cu")
		(at 30.949392 -395.641576)
		(property "Reference" "PC6639"
			(at 0 0 0)
			(layer "F.SilkS")
			(hide yes)
			(effects
				(font
					(size 1.27 1.27)
				)
			)
		)
		(property "Value" ""
			(at 0 0 0)
			(layer "F.Fab")
			(effects
				(font
					(size 1.27 1.27)
				)
			)
		)
		(duplicate_pad_numbers_are_jumpers no)
		(fp_line
			(start -1.524 -0.762)
			(end 1.524 -0.762)
			(stroke
				(width 0.1524)
				(type default)
			)
			(layer "F.SilkS")
		)
		(fp_line
			(start -1.524 0.762)
			(end -1.524 -0.762)
			(stroke
				(width 0.1524)
				(type default)
			)
			(layer "F.SilkS")
		)
		(fp_line
			(start 1.524 -0.762)
			(end 1.524 0.762)
			(stroke
				(width 0.1524)
				(type default)
			)
			(layer "F.SilkS")
		)
		(fp_line
			(start 1.524 0.762)
			(end -1.524 0.762)
			(stroke
				(width 0.1524)
				(type default)
			)
			(layer "F.SilkS")
		)
		(fp_line
			(start -1.1049 -0.724916)
			(end -1.1049 0.724916)
			(stroke
				(width 0.1)
				(type default)
			)
			(layer "F.Fab")
		)
		(fp_line
			(start -1.1049 0.724916)
			(end 1.1049 0.724916)
			(stroke
				(width 0.1)
				(type default)
			)
			(layer "F.Fab")
		)
		(fp_line
			(start 1.1049 -0.724916)
			(end -1.1049 -0.724916)
			(stroke
				(width 0.1)
				(type default)
			)
			(layer "F.Fab")
		)
		(fp_line
			(start 1.1049 0.724916)
			(end 1.1049 -0.724916)
			(stroke
				(width 0.1)
				(type default)
			)
			(layer "F.Fab")
		)
		(pad "1" smd rect
			(at -0.889 0 180)
			(size 1.016 1.27)
			(layers "F.Cu" "F.Mask" "F.Paste")
			(net "SW_P12V_AUX_P0V9_RETIMER_CPU1_FLT")
		)
		(pad "2" smd rect
			(at 0.889 0 180)
			(size 1.016 1.27)
			(layers "F.Cu" "F.Mask" "F.Paste")
			(net "GND")
		)
	)
	(footprint ""
		(layer "F.Cu")
		(at 125.095 -321.655948 90)
		(property "Reference" "R3353"
			(at 0 0 90)
			(layer "F.SilkS")
			(hide yes)
			(effects
				(font
					(size 1.27 1.27)
				)
			)
		)
		(property "Value" ""
			(at 0 0 90)
			(layer "F.Fab")
			(effects
				(font
					(size 1.27 1.27)
				)
			)
		)
		(duplicate_pad_numbers_are_jumpers no)
		(fp_line
			(start 0.7874 -0.4064)
			(end 0.7874 0.0508)
			(stroke
				(width 0.1524)
				(type default)
			)
			(layer "F.SilkS")
		)
		(fp_line
			(start -0.7874 -0.4064)
			(end 0.7874 -0.4064)
			(stroke
				(width 0.1524)
				(type default)
			)
			(layer "F.SilkS")
		)
		(fp_line
			(start -0.7874 -0.0508)
			(end -0.7874 -0.4064)
			(stroke
				(width 0.1524)
				(type default)
			)
			(layer "F.SilkS")
		)
		(fp_line
			(start 0.390652 0.4064)
			(end -0.371348 0.4064)
			(stroke
				(width 0.1524)
				(type default)
			)
			(layer "F.SilkS")
		)
		(fp_line
			(start -0.12065 -0.305054)
			(end -0.12065 -0.2794)
			(stroke
				(width 0.1)
				(type default)
			)
			(layer "F.Fab")
		)
		(fp_line
			(start -0.67945 -0.305054)
			(end -0.12065 -0.305054)
			(stroke
				(width 0.1)
				(type default)
			)
			(layer "F.Fab")
		)
		(fp_line
			(start 0.67945 -0.3048)
			(end 0.67945 0.3048)
			(stroke
				(width 0.1)
				(type default)
			)
			(layer "F.Fab")
		)
		(fp_line
			(start 0.12065 -0.3048)
			(end 0.67945 -0.3048)
			(stroke
				(width 0.1)
				(type default)
			)
			(layer "F.Fab")
		)
		(fp_line
			(start 0.12065 -0.2794)
			(end 0.12065 -0.3048)
			(stroke
				(width 0.1)
				(type default)
			)
			(layer "F.Fab")
		)
		(fp_line
			(start -0.12065 -0.2794)
			(end 0.12065 -0.2794)
			(stroke
				(width 0.1)
				(type default)
			)
			(layer "F.Fab")
		)
		(fp_line
			(start 0.120396 0.2794)
			(end -0.12065 0.2794)
			(stroke
				(width 0.1)
				(type default)
			)
			(layer "F.Fab")
		)
		(fp_line
			(start -0.12065 0.2794)
			(end -0.12065 0.3048)
			(stroke
				(width 0.1)
				(type default)
			)
			(layer "F.Fab")
		)
		(fp_line
			(start 0.67945 0.3048)
			(end 0.120396 0.3048)
			(stroke
				(width 0.1)
				(type default)
			)
			(layer "F.Fab")
		)
		(fp_line
			(start 0.120396 0.3048)
			(end 0.120396 0.2794)
			(stroke
				(width 0.1)
				(type default)
			)
			(layer "F.Fab")
		)
		(fp_line
			(start -0.12065 0.3048)
			(end -0.67945 0.3048)
			(stroke
				(width 0.1)
				(type default)
			)
			(layer "F.Fab")
		)
		(fp_line
			(start -0.67945 0.3048)
			(end -0.67945 -0.305054)
			(stroke
				(width 0.1)
				(type default)
			)
			(layer "F.Fab")
		)
		(pad "1" smd circle
			(at -0.40005 0 90)
			(size 0 0)
			(layers "F.Cu" "F.Mask" "F.Paste")
			(net "CLK_100M_CPU1_CLK11_R_DN")
		)
		(pad "2" smd circle
			(at 0.40005 0 90)
			(size 0 0)
			(layers "F.Cu" "F.Mask" "F.Paste")
			(net "CLK_100M_CPU1_CLK11_DN")
		)
	)
	(footprint ""
		(layer "F.Cu")
		(at 394.947394 -58.8645 180)
		(property "Reference" "J54"
			(at -0.614172 -7.543292 0)
			(unlocked yes)
			(layer "F.SilkS")
			(effects
				(font
					(size 0.7874 0.5842)
					(thickness 0.1524)
				)
			)
		)
		(property "Value" ""
			(at 0 0 180)
			(layer "F.Fab")
			(effects
				(font
					(size 1.27 1.27)
				)
			)
		)
		(duplicate_pad_numbers_are_jumpers no)
		(fp_line
			(start 2.249932 6.35)
			(end -2.249932 6.35)
			(stroke
				(width 0.1524)
				(type default)
			)
			(layer "F.SilkS")
		)
		(fp_line
			(start 2.249932 6.2738)
			(end 2.249932 6.35)
			(stroke
				(width 0.1524)
				(type default)
			)
			(layer "F.SilkS")
		)
		(fp_line
			(start 2.249932 5.1562)
			(end 2.249932 5.0038)
			(stroke
				(width 0.1524)
				(type default)
			)
			(layer "F.SilkS")
		)
		(fp_line
			(start 2.249932 3.8862)
			(end 2.249932 3.7338)
			(stroke
				(width 0.1524)
				(type default)
			)
			(layer "F.SilkS")
		)
		(fp_line
			(start 2.249932 2.6162)
			(end 2.249932 2.4638)
			(stroke
				(width 0.1524)
				(type default)
			)
			(layer "F.SilkS")
		)
		(fp_line
			(start 2.249932 1.3462)
			(end 2.249932 1.1938)
			(stroke
				(width 0.1524)
				(type default)
			)
			(layer "F.SilkS")
		)
		(fp_line
			(start 2.249932 0.0762)
			(end 2.249932 -0.0762)
			(stroke
				(width 0.1524)
				(type default)
			)
			(layer "F.SilkS")
		)
		(fp_line
			(start 2.249932 -1.1938)
			(end 2.249932 -1.3462)
			(stroke
				(width 0.1524)
				(type default)
			)
			(layer "F.SilkS")
		)
		(fp_line
			(start 2.249932 -2.4638)
			(end 2.249932 -2.6162)
			(stroke
				(width 0.1524)
				(type default)
			)
			(layer "F.SilkS")
		)
		(fp_line
			(start 2.249932 -3.7338)
			(end 2.249932 -3.8862)
			(stroke
				(width 0.1524)
				(type default)
			)
			(layer "F.SilkS")
		)
		(fp_line
			(start 2.249932 -5.0038)
			(end 2.249932 -5.1562)
			(stroke
				(width 0.1524)
				(type default)
			)
			(layer "F.SilkS")
		)
		(fp_line
			(start 2.249932 -6.35)
			(end 2.249932 -6.2738)
			(stroke
				(width 0.1524)
				(type default)
			)
			(layer "F.SilkS")
		)
		(fp_line
			(start -2.249932 6.35)
			(end -2.249932 6.2738)
			(stroke
				(width 0.1524)
				(type default)
			)
			(layer "F.SilkS")
		)
		(fp_line
			(start -2.249932 5.1562)
			(end -2.249932 5.0038)
			(stroke
				(width 0.1524)
				(type default)
			)
			(layer "F.SilkS")
		)
		(fp_line
			(start -2.249932 3.8862)
			(end -2.249932 3.7338)
			(stroke
				(width 0.1524)
				(type default)
			)
			(layer "F.SilkS")
		)
		(fp_line
			(start -2.249932 2.6162)
			(end -2.249932 2.4638)
			(stroke
				(width 0.1524)
				(type default)
			)
			(layer "F.SilkS")
		)
		(fp_line
			(start -2.249932 1.3462)
			(end -2.249932 1.1938)
			(stroke
				(width 0.1524)
				(type default)
			)
			(layer "F.SilkS")
		)
		(fp_line
			(start -2.249932 0.0762)
			(end -2.249932 -0.0762)
			(stroke
				(width 0.1524)
				(type default)
			)
			(layer "F.SilkS")
		)
		(fp_line
			(start -2.249932 -1.1938)
			(end -2.249932 -1.3462)
			(stroke
				(width 0.1524)
				(type default)
			)
			(layer "F.SilkS")
		)
		(fp_line
			(start -2.249932 -2.4638)
			(end -2.249932 -2.6162)
			(stroke
				(width 0.1524)
				(type default)
			)
			(layer "F.SilkS")
		)
		(fp_line
			(start -2.249932 -3.7338)
			(end -2.249932 -3.8862)
			(stroke
				(width 0.1524)
				(type default)
			)
			(layer "F.SilkS")
		)
		(fp_line
			(start -2.249932 -5.0038)
			(end -2.249932 -5.1562)
			(stroke
				(width 0.1524)
				(type default)
			)
			(layer "F.SilkS")
		)
		(fp_line
			(start -2.249932 -6.2738)
			(end -2.249932 -6.35)
			(stroke
				(width 0.1524)
				(type default)
			)
			(layer "F.SilkS")
		)
		(fp_line
			(start -2.249932 -6.35)
			(end 2.249932 -6.35)
			(stroke
				(width 0.1524)
				(type default)
			)
			(layer "F.SilkS")
		)
		(fp_poly
			(pts
				(xy -3.706114 -5.715) (xy -4.722114 -5.207) (xy -4.722114 -6.223)
			)
			(stroke
				(width 0)
				(type default)
			)
			(fill yes)
			(layer "F.SilkS")
		)
		(fp_line
			(start 2.249932 6.35)
			(end -2.249932 6.35)
			(stroke
				(width 0.1)
				(type default)
			)
			(layer "F.Fab")
		)
		(fp_line
			(start 2.249932 -6.35)
			(end 2.249932 6.35)
			(stroke
				(width 0.1)
				(type default)
			)
			(layer "F.Fab")
		)
		(fp_line
			(start -2.249932 6.35)
			(end -2.249932 -6.35)
			(stroke
				(width 0.1)
				(type default)
			)
			(layer "F.Fab")
		)
		(fp_line
			(start -2.249932 -6.35)
			(end 2.249932 -6.35)
			(stroke
				(width 0.1)
				(type default)
			)
			(layer "F.Fab")
		)
		(fp_poly
			(pts
				(xy -4.722114 -6.223) (xy -4.722114 -5.207) (xy -3.706114 -5.715)
			)
			(stroke
				(width 0)
				(type default)
			)
			(fill yes)
			(layer "F.Fab")
		)
		(pad "1" smd rect
			(at -2.359914 -5.715 90)
			(size 0.8636 2.4384)
			(layers "F.Cu" "F.Mask" "F.Paste")
			(net "PVDD18_S5_P0")
		)
		(pad "2" smd rect
			(at 2.359914 -5.715 90)
			(size 0.8636 2.4384)
			(layers "F.Cu" "F.Mask" "F.Paste")
			(net "HDT_HDR_R_TCK")
		)
		(pad "3" smd rect
			(at -2.359914 -4.445 90)
			(size 0.8636 2.4384)
			(layers "F.Cu" "F.Mask" "F.Paste")
			(net "PRSNT_HDT_R_N")
		)
		(pad "4" smd rect
			(at 2.359914 -4.445 90)
			(size 0.8636 2.4384)
			(layers "F.Cu" "F.Mask" "F.Paste")
			(net "HDT_HDR_R_TMS")
		)
		(pad "5" smd rect
			(at -2.359914 -3.175 90)
			(size 0.8636 2.4384)
			(layers "F.Cu" "F.Mask" "F.Paste")
			(net "GND")
		)
		(pad "6" smd rect
			(at 2.359914 -3.175 90)
			(size 0.8636 2.4384)
			(layers "F.Cu" "F.Mask" "F.Paste")
			(net "HDT_HDR_R_TDI")
		)
		(pad "7" smd rect
			(at -2.359914 -1.905 90)
			(size 0.8636 2.4384)
			(layers "F.Cu" "F.Mask" "F.Paste")
			(net "GND")
		)
		(pad "8" smd rect
			(at 2.359914 -1.905 90)
			(size 0.8636 2.4384)
			(layers "F.Cu" "F.Mask" "F.Paste")
			(net "HDT_HDR_TDO")
		)
		(pad "9" smd rect
			(at -2.359914 -0.635 90)
			(size 0.8636 2.4384)
			(layers "F.Cu" "F.Mask" "F.Paste")
			(net "HDT_HDR_TRST_N_R")
		)
		(pad "10" smd rect
			(at 2.359914 -0.635 90)
			(size 0.8636 2.4384)
			(layers "F.Cu" "F.Mask" "F.Paste")
			(net "HDT_HDR_PWROK")
		)
		(pad "11" smd rect
			(at -2.359914 0.635 90)
			(size 0.8636 2.4384)
			(layers "F.Cu" "F.Mask" "F.Paste")
			(net "HDT_CPU0_XTRIG_L6")
		)
		(pad "12" smd rect
			(at 2.359914 0.635 90)
			(size 0.8636 2.4384)
			(layers "F.Cu" "F.Mask" "F.Paste")
			(net "HDT_HDR_RESET_N")
		)
		(pad "13" smd rect
			(at -2.359914 1.905 90)
			(size 0.8636 2.4384)
			(layers "F.Cu" "F.Mask" "F.Paste")
			(net "HDT_CPU0_XTRIG_L7")
		)
		(pad "14" smd rect
			(at 2.359914 1.905 90)
			(size 0.8636 2.4384)
			(layers "F.Cu" "F.Mask" "F.Paste")
			(net "Net_10739")
		)
		(pad "15" smd rect
			(at -2.359914 3.175 90)
			(size 0.8636 2.4384)
			(layers "F.Cu" "F.Mask" "F.Paste")
			(net "HDT_CPU0_XTRIG_L5")
		)
		(pad "16" smd rect
			(at 2.359914 3.175 90)
			(size 0.8636 2.4384)
			(layers "F.Cu" "F.Mask" "F.Paste")
			(net "HDT_HDR_DBREQ_R_N")
		)
		(pad "17" smd rect
			(at -2.359914 4.445 90)
			(size 0.8636 2.4384)
			(layers "F.Cu" "F.Mask" "F.Paste")
			(net "GND")
		)
		(pad "18" smd rect
			(at 2.359914 4.445 90)
			(size 0.8636 2.4384)
			(layers "F.Cu" "F.Mask" "F.Paste")
			(net "HDT_CPU0_HDT_CONN_TESTEN")
		)
		(pad "19" smd rect
			(at -2.359914 5.715 90)
			(size 0.8636 2.4384)
			(layers "F.Cu" "F.Mask" "F.Paste")
			(net "PVDD18_S5_P0")
		)
		(pad "20" smd rect
			(at 2.359914 5.715 90)
			(size 0.8636 2.4384)
			(layers "F.Cu" "F.Mask" "F.Paste")
			(net "Net_10738")
		)
	)
	(footprint ""
		(layer "F.Cu")
		(at 182.912766 -164.761418 90)
		(property "Reference" "U108"
			(at 0.488188 3.023108 90)
			(unlocked yes)
			(layer "F.SilkS")
			(effects
				(font
					(size 0.7874 0.5842)
					(thickness 0.1524)
				)
			)
		)
		(property "Value" ""
			(at 0 0 90)
			(layer "F.Fab")
			(effects
				(font
					(size 1.27 1.27)
				)
			)
		)
		(duplicate_pad_numbers_are_jumpers no)
		(fp_line
			(start 1.03378 -1.284478)
			(end 1.03378 1.284478)
			(stroke
				(width 0.1524)
				(type default)
			)
			(layer "F.SilkS")
		)
		(fp_line
			(start -1.03378 -1.284478)
			(end 1.03378 -1.284478)
			(stroke
				(width 0.1524)
				(type default)
			)
			(layer "F.SilkS")
		)
		(fp_line
			(start 1.03378 1.284478)
			(end -1.03378 1.284478)
			(stroke
				(width 0.1524)
				(type default)
			)
			(layer "F.SilkS")
		)
		(fp_line
			(start -1.03378 1.284478)
			(end -1.03378 -1.284478)
			(stroke
				(width 0.1524)
				(type default)
			)
			(layer "F.SilkS")
		)
		(fp_poly
			(pts
				(xy -1.806702 -1.052576) (xy -1.201674 -0.750062) (xy -1.806702 -0.447548)
			)
			(stroke
				(width 0)
				(type default)
			)
			(fill yes)
			(layer "F.SilkS")
		)
		(fp_line
			(start 0.774954 -1.02489)
			(end 0.774954 1.02489)
			(stroke
				(width 0.1)
				(type default)
			)
			(layer "F.Fab")
		)
		(fp_line
			(start -0.774954 -1.02489)
			(end 0.774954 -1.02489)
			(stroke
				(width 0.1)
				(type default)
			)
			(layer "F.Fab")
		)
		(fp_line
			(start 0.774954 1.02489)
			(end -0.774954 1.02489)
			(stroke
				(width 0.1)
				(type default)
			)
			(layer "F.Fab")
		)
		(fp_line
			(start -0.774954 1.02489)
			(end -0.774954 -1.02489)
			(stroke
				(width 0.1)
				(type default)
			)
			(layer "F.Fab")
		)
		(fp_poly
			(pts
				(xy -1.201674 -0.750062) (xy -1.806702 -0.447548) (xy -1.806702 -1.052576)
			)
			(stroke
				(width 0)
				(type default)
			)
			(fill yes)
			(layer "F.Fab")
		)
		(pad "1" smd rect
			(at -0.64008 -0.750062 180)
			(size 0.3048 0.5334)
			(layers "F.Cu" "F.Mask" "F.Paste")
			(net "I3C_1_SPD_DDRGL_CPU1_SCL")
		)
		(pad "2" smd rect
			(at -0.64008 -0.249936 180)
			(size 0.254 0.5334)
			(layers "F.Cu" "F.Mask" "F.Paste")
			(net "I3C_1_SPD_DDRGL_CPU1_SDA")
		)
		(pad "3" smd rect
			(at -0.64008 0.249936 180)
			(size 0.254 0.5334)
			(layers "F.Cu" "F.Mask" "F.Paste")
			(net "I3C_SCM_3_R_SCL")
		)
		(pad "4" smd rect
			(at -0.64008 0.750062 180)
			(size 0.3048 0.5334)
			(layers "F.Cu" "F.Mask" "F.Paste")
			(net "I3C_SCM_3_R_SDA")
		)
		(pad "5" smd rect
			(at 0 0.839978 90)
			(size 0.3302 0.635)
			(layers "F.Cu" "F.Mask" "F.Paste")
			(net "GND")
		)
		(pad "6" smd rect
			(at 0.64008 0.750062 180)
			(size 0.3048 0.5334)
			(layers "F.Cu" "F.Mask" "F.Paste")
			(net "FM_I3C_CPU1_MUX1_OE_N")
		)
		(pad "7" smd rect
			(at 0.64008 0.249936 180)
			(size 0.254 0.5334)
			(layers "F.Cu" "F.Mask" "F.Paste")
			(net "I3C_SPD_DDRGL_CPU1_LVC1_SDA")
		)
		(pad "8" smd rect
			(at 0.64008 -0.249936 180)
			(size 0.254 0.5334)
			(layers "F.Cu" "F.Mask" "F.Paste")
			(net "I3C_SPD_DDRGL_CPU1_LVC1_SCL")
		)
		(pad "9" smd rect
			(at 0.64008 -0.750062 180)
			(size 0.3048 0.5334)
			(layers "F.Cu" "F.Mask" "F.Paste")
			(net "FM_I3C_CPU1_MUX1_SEL")
		)
		(pad "10" smd rect
			(at 0 -0.839978 90)
			(size 0.3302 0.635)
			(layers "F.Cu" "F.Mask" "F.Paste")
			(net "P3V3_AUX")
		)
	)
)
